FILE_TYPE = MACRO_DRAWING;
SET COLOR_WIRE YELLOW;
SET COLOR_PROP ORANGE;
SET COLOR_DOT WHITE;
SET COLOR_ARC YELLOW;
SET COLOR_BODY GREEN;
SET COLOR_NOTE PURPLE;
SET PROP_DISPLAY VALUE;
SET PAGE_NUMBER P60;
FORCEADD UNIVERSAL_GND..1
R 1
(-1075 4675);
FORCEPROP 3 LASTPIN (-1125 4675) SIG_NAME GND\g
J 0
(-1115 4685);
DISPLAY 0.659574 (-1115 4685);
PAINT MONO (-1115 4685);
DISPLAY INVISIBLE (-1115 4685);
FORCEPROP 2 LAST CDS_LIB pure_quanta_power
J 0
(-1075 4675);
DISPLAY INVISIBLE (-1075 4675);
FORCEPROP 1 LAST PATH I1
R 1
J 0
(-1075 4750);
DISPLAY 0.872340 (-1075 4750);
PAINT AQUA (-1075 4750);
DISPLAY INVISIBLE (-1075 4750);
FORCEPROP 1 LAST HDL_POWER GND
R 1
J 1
(-1000 4700);
DISPLAY 0.872340 (-1000 4700);
PAINT GREEN (-1000 4700);
DISPLAY INVISIBLE (-1000 4700);
FORCEADD UNIVERSAL_GND..1
R 1
(-1650 3225);
FORCEPROP 3 LASTPIN (-1700 3225) SIG_NAME GND\g
J 0
(-1690 3235);
DISPLAY 0.659574 (-1690 3235);
PAINT MONO (-1690 3235);
DISPLAY INVISIBLE (-1690 3235);
FORCEPROP 2 LAST CDS_LIB pure_quanta_power
J 0
(-1650 3225);
DISPLAY INVISIBLE (-1650 3225);
FORCEPROP 1 LAST PATH I2
R 1
J 0
(-1650 3300);
DISPLAY 0.872340 (-1650 3300);
PAINT AQUA (-1650 3300);
DISPLAY INVISIBLE (-1650 3300);
FORCEPROP 1 LAST HDL_POWER GND
R 1
J 1
(-1575 3250);
DISPLAY 0.872340 (-1575 3250);
PAINT GREEN (-1575 3250);
DISPLAY INVISIBLE (-1575 3250);
FORCEADD GENOA_SP5..40
R 1
(-4525 3950);
FORCEPROP 1 LAST LOCATION U26
R 1
J 0
(-8181 3555);
DISPLAY 0.489362 (-8181 3555);
PAINT SKYBLUE (-8181 3555);
FORCEPROP 0 LAST $SEC 40
R 1
J 0
(-1175 4525);
DISPLAY 0.680851 (-1175 4525);
PAINT MONO (-1175 4525);
DISPLAY INVISIBLE (-1175 4525);
FORCEPROP 0 LAST CDS_SEC 40
R 1
J 0
(-1175 4525);
DISPLAY 1.021277 (-1175 4525);
DISPLAY INVISIBLE (-1175 4525);
FORCEPROP 0 LASTPIN (-2425 4500) $PN AA42
R 1
J 0
(-2435 4510);
DISPLAY 0.489362 (-2435 4510);
PAINT MONO (-2435 4510);
FORCEPROP 0 LASTPIN (-2375 4500) $PN AA72
R 1
J 0
(-2385 4510);
DISPLAY 0.489362 (-2385 4510);
PAINT MONO (-2385 4510);
FORCEPROP 0 LASTPIN (-2325 4500) $PN AD31
R 1
J 0
(-2335 4510);
DISPLAY 0.489362 (-2335 4510);
PAINT MONO (-2335 4510);
FORCEPROP 0 LASTPIN (-2275 4500) $PN AE4
R 1
J 0
(-2285 4510);
DISPLAY 0.489362 (-2285 4510);
PAINT MONO (-2285 4510);
FORCEPROP 0 LASTPIN (-2225 4500) $PN AH33
R 1
J 0
(-2235 4510);
DISPLAY 0.489362 (-2235 4510);
PAINT MONO (-2235 4510);
FORCEPROP 0 LASTPIN (-2175 4500) $PN AJ13
R 1
J 0
(-2185 4510);
DISPLAY 0.489362 (-2185 4510);
PAINT MONO (-2185 4510);
FORCEPROP 0 LASTPIN (-2125 4500) $PN AM37
R 1
J 0
(-2135 4510);
DISPLAY 0.489362 (-2135 4510);
PAINT MONO (-2135 4510);
FORCEPROP 0 LASTPIN (-2075 4500) $PN AN20
R 1
J 0
(-2085 4510);
DISPLAY 0.489362 (-2085 4510);
PAINT MONO (-2085 4510);
FORCEPROP 0 LASTPIN (-2025 4500) $PN BV42
R 1
J 0
(-2035 4510);
DISPLAY 0.489362 (-2035 4510);
PAINT MONO (-2035 4510);
FORCEPROP 0 LASTPIN (-1975 4500) $PN BW25
R 1
J 0
(-1985 4510);
DISPLAY 0.489362 (-1985 4510);
PAINT MONO (-1985 4510);
FORCEPROP 0 LASTPIN (-1925 4500) $PN CB44
R 1
J 0
(-1935 4510);
DISPLAY 0.489362 (-1935 4510);
PAINT MONO (-1935 4510);
FORCEPROP 0 LASTPIN (-1875 4500) $PN CC22
R 1
J 0
(-1885 4510);
DISPLAY 0.489362 (-1885 4510);
PAINT MONO (-1885 4510);
FORCEPROP 0 LASTPIN (-1825 4500) $PN CF46
R 1
J 0
(-1835 4510);
DISPLAY 0.489362 (-1835 4510);
PAINT MONO (-1835 4510);
FORCEPROP 0 LASTPIN (-1775 4500) $PN CG42
R 1
J 0
(-1785 4510);
DISPLAY 0.489362 (-1785 4510);
PAINT MONO (-1785 4510);
FORCEPROP 0 LASTPIN (-1725 4500) $PN CK10
R 1
J 0
(-1735 4510);
DISPLAY 0.489362 (-1735 4510);
PAINT MONO (-1735 4510);
FORCEPROP 0 LASTPIN (-1675 4500) $PN CK31
R 1
J 0
(-1685 4510);
DISPLAY 0.489362 (-1685 4510);
PAINT MONO (-1685 4510);
FORCEPROP 0 LASTPIN (-1625 4500) $PN CM50
R 1
J 0
(-1635 4510);
DISPLAY 0.489362 (-1635 4510);
PAINT MONO (-1635 4510);
FORCEPROP 0 LASTPIN (-1575 4500) $PN CN54
R 1
J 0
(-1585 4510);
DISPLAY 0.489362 (-1585 4510);
PAINT MONO (-1585 4510);
FORCEPROP 0 LASTPIN (-1525 4500) $PN CT52
R 1
J 0
(-1535 4510);
DISPLAY 0.489362 (-1535 4510);
PAINT MONO (-1535 4510);
FORCEPROP 0 LASTPIN (-1475 4500) $PN CU58
R 1
J 0
(-1485 4510);
DISPLAY 0.489362 (-1485 4510);
PAINT MONO (-1485 4510);
FORCEPROP 0 LASTPIN (-1425 4500) $PN CY57
R 1
J 0
(-1435 4510);
DISPLAY 0.489362 (-1435 4510);
PAINT MONO (-1435 4510);
FORCEPROP 0 LASTPIN (-1375 4500) $PN DA56
R 1
J 0
(-1385 4510);
DISPLAY 0.489362 (-1385 4510);
PAINT MONO (-1385 4510);
FORCEPROP 0 LASTPIN (-7775 3400) $PN DA72
R 1
J 2
(-7785 3390);
DISPLAY 0.489362 (-7785 3390);
PAINT MONO (-7785 3390);
FORCEPROP 0 LASTPIN (-7725 3400) $PN DA75
R 1
J 2
(-7735 3390);
DISPLAY 0.489362 (-7735 3390);
PAINT MONO (-7735 3390);
FORCEPROP 0 LASTPIN (-7675 3400) $PN DB3
R 1
J 2
(-7685 3390);
DISPLAY 0.489362 (-7685 3390);
PAINT MONO (-7685 3390);
FORCEPROP 0 LASTPIN (-7625 3400) $PN DB8
R 1
J 2
(-7635 3390);
DISPLAY 0.489362 (-7635 3390);
PAINT MONO (-7635 3390);
FORCEPROP 0 LASTPIN (-7575 3400) $PN DB10
R 1
J 2
(-7585 3390);
DISPLAY 0.489362 (-7585 3390);
PAINT MONO (-7585 3390);
FORCEPROP 0 LASTPIN (-7525 3400) $PN DB15
R 1
J 2
(-7535 3390);
DISPLAY 0.489362 (-7535 3390);
PAINT MONO (-7535 3390);
FORCEPROP 0 LASTPIN (-7475 3400) $PN DB17
R 1
J 2
(-7485 3390);
DISPLAY 0.489362 (-7485 3390);
PAINT MONO (-7485 3390);
FORCEPROP 0 LASTPIN (-7425 3400) $PN DB22
R 1
J 2
(-7435 3390);
DISPLAY 0.489362 (-7435 3390);
PAINT MONO (-7435 3390);
FORCEPROP 0 LASTPIN (-7375 3400) $PN DB25
R 1
J 2
(-7385 3390);
DISPLAY 0.489362 (-7385 3390);
PAINT MONO (-7385 3390);
FORCEPROP 0 LASTPIN (-7325 3400) $PN DB28
R 1
J 2
(-7335 3390);
DISPLAY 0.489362 (-7335 3390);
PAINT MONO (-7335 3390);
FORCEPROP 0 LASTPIN (-7275 3400) $PN DB31
R 1
J 2
(-7285 3390);
DISPLAY 0.489362 (-7285 3390);
PAINT MONO (-7285 3390);
FORCEPROP 0 LASTPIN (-7225 3400) $PN DB34
R 1
J 2
(-7235 3390);
DISPLAY 0.489362 (-7235 3390);
PAINT MONO (-7235 3390);
FORCEPROP 0 LASTPIN (-7175 3400) $PN DB37
R 1
J 2
(-7185 3390);
DISPLAY 0.489362 (-7185 3390);
PAINT MONO (-7185 3390);
FORCEPROP 0 LASTPIN (-7125 3400) $PN DB39
R 1
J 2
(-7135 3390);
DISPLAY 0.489362 (-7135 3390);
PAINT MONO (-7135 3390);
FORCEPROP 0 LASTPIN (-7075 3400) $PN DB42
R 1
J 2
(-7085 3390);
DISPLAY 0.489362 (-7085 3390);
PAINT MONO (-7085 3390);
FORCEPROP 0 LASTPIN (-7025 3400) $PN DB45
R 1
J 2
(-7035 3390);
DISPLAY 0.489362 (-7035 3390);
PAINT MONO (-7035 3390);
FORCEPROP 0 LASTPIN (-6975 3400) $PN DB48
R 1
J 2
(-6985 3390);
DISPLAY 0.489362 (-6985 3390);
PAINT MONO (-6985 3390);
FORCEPROP 0 LASTPIN (-6925 3400) $PN DB51
R 1
J 2
(-6935 3390);
DISPLAY 0.489362 (-6935 3390);
PAINT MONO (-6935 3390);
FORCEPROP 0 LASTPIN (-6875 3400) $PN DB54
R 1
J 2
(-6885 3390);
DISPLAY 0.489362 (-6885 3390);
PAINT MONO (-6885 3390);
FORCEPROP 0 LASTPIN (-6825 3400) $PN DB59
R 1
J 2
(-6835 3390);
DISPLAY 0.489362 (-6835 3390);
PAINT MONO (-6835 3390);
FORCEPROP 0 LASTPIN (-6775 3400) $PN DB61
R 1
J 2
(-6785 3390);
DISPLAY 0.489362 (-6785 3390);
PAINT MONO (-6785 3390);
FORCEPROP 0 LASTPIN (-6725 3400) $PN DB66
R 1
J 2
(-6735 3390);
DISPLAY 0.489362 (-6735 3390);
PAINT MONO (-6735 3390);
FORCEPROP 0 LASTPIN (-6675 3400) $PN DB68
R 1
J 2
(-6685 3390);
DISPLAY 0.489362 (-6685 3390);
PAINT MONO (-6685 3390);
FORCEPROP 0 LASTPIN (-6625 3400) $PN DB73
R 1
J 2
(-6635 3390);
DISPLAY 0.489362 (-6635 3390);
PAINT MONO (-6635 3390);
FORCEPROP 0 LASTPIN (-6575 3400) $PN DC1
R 1
J 2
(-6585 3390);
DISPLAY 0.489362 (-6585 3390);
PAINT MONO (-6585 3390);
FORCEPROP 0 LASTPIN (-6525 3400) $PN DC4
R 1
J 2
(-6535 3390);
DISPLAY 0.489362 (-6535 3390);
PAINT MONO (-6535 3390);
FORCEPROP 0 LASTPIN (-6475 3400) $PN DC6
R 1
J 2
(-6485 3390);
DISPLAY 0.489362 (-6485 3390);
PAINT MONO (-6485 3390);
FORCEPROP 0 LASTPIN (-6425 3400) $PN DC8
R 1
J 2
(-6435 3390);
DISPLAY 0.489362 (-6435 3390);
PAINT MONO (-6435 3390);
FORCEPROP 0 LASTPIN (-6375 3400) $PN DC11
R 1
J 2
(-6385 3390);
DISPLAY 0.489362 (-6385 3390);
PAINT MONO (-6385 3390);
FORCEPROP 0 LASTPIN (-6325 3400) $PN DC13
R 1
J 2
(-6335 3390);
DISPLAY 0.489362 (-6335 3390);
PAINT MONO (-6335 3390);
FORCEPROP 0 LASTPIN (-6275 3400) $PN DC15
R 1
J 2
(-6285 3390);
DISPLAY 0.489362 (-6285 3390);
PAINT MONO (-6285 3390);
FORCEPROP 0 LASTPIN (-6225 3400) $PN DC18
R 1
J 2
(-6235 3390);
DISPLAY 0.489362 (-6235 3390);
PAINT MONO (-6235 3390);
FORCEPROP 0 LASTPIN (-6175 3400) $PN DC20
R 1
J 2
(-6185 3390);
DISPLAY 0.489362 (-6185 3390);
PAINT MONO (-6185 3390);
FORCEPROP 0 LASTPIN (-6125 3400) $PN DC22
R 1
J 2
(-6135 3390);
DISPLAY 0.489362 (-6135 3390);
PAINT MONO (-6135 3390);
FORCEPROP 0 LASTPIN (-6075 3400) $PN DC25
R 1
J 2
(-6085 3390);
DISPLAY 0.489362 (-6085 3390);
PAINT MONO (-6085 3390);
FORCEPROP 0 LASTPIN (-6025 3400) $PN DC28
R 1
J 2
(-6035 3390);
DISPLAY 0.489362 (-6035 3390);
PAINT MONO (-6035 3390);
FORCEPROP 0 LASTPIN (-5975 3400) $PN DC31
R 1
J 2
(-5985 3390);
DISPLAY 0.489362 (-5985 3390);
PAINT MONO (-5985 3390);
FORCEPROP 0 LASTPIN (-5925 3400) $PN DC34
R 1
J 2
(-5935 3390);
DISPLAY 0.489362 (-5935 3390);
PAINT MONO (-5935 3390);
FORCEPROP 0 LASTPIN (-5875 3400) $PN DC42
R 1
J 2
(-5885 3390);
DISPLAY 0.489362 (-5885 3390);
PAINT MONO (-5885 3390);
FORCEPROP 0 LASTPIN (-5825 3400) $PN DC45
R 1
J 2
(-5835 3390);
DISPLAY 0.489362 (-5835 3390);
PAINT MONO (-5835 3390);
FORCEPROP 0 LASTPIN (-5775 3400) $PN DC48
R 1
J 2
(-5785 3390);
DISPLAY 0.489362 (-5785 3390);
PAINT MONO (-5785 3390);
FORCEPROP 0 LASTPIN (-5725 3400) $PN DC51
R 1
J 2
(-5735 3390);
DISPLAY 0.489362 (-5735 3390);
PAINT MONO (-5735 3390);
FORCEPROP 0 LASTPIN (-5675 3400) $PN DC54
R 1
J 2
(-5685 3390);
DISPLAY 0.489362 (-5685 3390);
PAINT MONO (-5685 3390);
FORCEPROP 0 LASTPIN (-5625 3400) $PN DC56
R 1
J 2
(-5635 3390);
DISPLAY 0.489362 (-5635 3390);
PAINT MONO (-5635 3390);
FORCEPROP 0 LASTPIN (-5575 3400) $PN DC58
R 1
J 2
(-5585 3390);
DISPLAY 0.489362 (-5585 3390);
PAINT MONO (-5585 3390);
FORCEPROP 0 LASTPIN (-5525 3400) $PN DC61
R 1
J 2
(-5535 3390);
DISPLAY 0.489362 (-5535 3390);
PAINT MONO (-5535 3390);
FORCEPROP 0 LASTPIN (-5475 3400) $PN DC63
R 1
J 2
(-5485 3390);
DISPLAY 0.489362 (-5485 3390);
PAINT MONO (-5485 3390);
FORCEPROP 0 LASTPIN (-5425 3400) $PN DC65
R 1
J 2
(-5435 3390);
DISPLAY 0.489362 (-5435 3390);
PAINT MONO (-5435 3390);
FORCEPROP 0 LASTPIN (-5375 3400) $PN DC68
R 1
J 2
(-5385 3390);
DISPLAY 0.489362 (-5385 3390);
PAINT MONO (-5385 3390);
FORCEPROP 0 LASTPIN (-5325 3400) $PN DC70
R 1
J 2
(-5335 3390);
DISPLAY 0.489362 (-5335 3390);
PAINT MONO (-5335 3390);
FORCEPROP 0 LASTPIN (-5275 3400) $PN DC72
R 1
J 2
(-5285 3390);
DISPLAY 0.489362 (-5285 3390);
PAINT MONO (-5285 3390);
FORCEPROP 0 LASTPIN (-5225 3400) $PN DC75
R 1
J 2
(-5235 3390);
DISPLAY 0.489362 (-5235 3390);
PAINT MONO (-5235 3390);
FORCEPROP 0 LASTPIN (-5175 3400) $PN DD3
R 1
J 2
(-5185 3390);
DISPLAY 0.489362 (-5185 3390);
PAINT MONO (-5185 3390);
FORCEPROP 0 LASTPIN (-5125 3400) $PN DD5
R 1
J 2
(-5135 3390);
DISPLAY 0.489362 (-5135 3390);
PAINT MONO (-5135 3390);
FORCEPROP 0 LASTPIN (-5075 3400) $PN DD8
R 1
J 2
(-5085 3390);
DISPLAY 0.489362 (-5085 3390);
PAINT MONO (-5085 3390);
FORCEPROP 0 LASTPIN (-5025 3400) $PN DD10
R 1
J 2
(-5035 3390);
DISPLAY 0.489362 (-5035 3390);
PAINT MONO (-5035 3390);
FORCEPROP 0 LASTPIN (-4975 3400) $PN DD12
R 1
J 2
(-4985 3390);
DISPLAY 0.489362 (-4985 3390);
PAINT MONO (-4985 3390);
FORCEPROP 0 LASTPIN (-4925 3400) $PN DD15
R 1
J 2
(-4935 3390);
DISPLAY 0.489362 (-4935 3390);
PAINT MONO (-4935 3390);
FORCEPROP 0 LASTPIN (-4875 3400) $PN DD17
R 1
J 2
(-4885 3390);
DISPLAY 0.489362 (-4885 3390);
PAINT MONO (-4885 3390);
FORCEPROP 0 LASTPIN (-4825 3400) $PN DD19
R 1
J 2
(-4835 3390);
DISPLAY 0.489362 (-4835 3390);
PAINT MONO (-4835 3390);
FORCEPROP 0 LASTPIN (-4775 3400) $PN DD23
R 1
J 2
(-4785 3390);
DISPLAY 0.489362 (-4785 3390);
PAINT MONO (-4785 3390);
FORCEPROP 0 LASTPIN (-4725 3400) $PN DD24
R 1
J 2
(-4735 3390);
DISPLAY 0.489362 (-4735 3390);
PAINT MONO (-4735 3390);
FORCEPROP 0 LASTPIN (-4675 3400) $PN DD26
R 1
J 2
(-4685 3390);
DISPLAY 0.489362 (-4685 3390);
PAINT MONO (-4685 3390);
FORCEPROP 0 LASTPIN (-4625 3400) $PN DD27
R 1
J 2
(-4635 3390);
DISPLAY 0.489362 (-4635 3390);
PAINT MONO (-4635 3390);
FORCEPROP 0 LASTPIN (-4575 3400) $PN DD29
R 1
J 2
(-4585 3390);
DISPLAY 0.489362 (-4585 3390);
PAINT MONO (-4585 3390);
FORCEPROP 0 LASTPIN (-4525 3400) $PN DD30
R 1
J 2
(-4535 3390);
DISPLAY 0.489362 (-4535 3390);
PAINT MONO (-4535 3390);
FORCEPROP 0 LASTPIN (-4475 3400) $PN DD32
R 1
J 2
(-4485 3390);
DISPLAY 0.489362 (-4485 3390);
PAINT MONO (-4485 3390);
FORCEPROP 0 LASTPIN (-4425 3400) $PN DD33
R 1
J 2
(-4435 3390);
DISPLAY 0.489362 (-4435 3390);
PAINT MONO (-4435 3390);
FORCEPROP 0 LASTPIN (-4375 3400) $PN DD35
R 1
J 2
(-4385 3390);
DISPLAY 0.489362 (-4385 3390);
PAINT MONO (-4385 3390);
FORCEPROP 0 LASTPIN (-4325 3400) $PN DD36
R 1
J 2
(-4335 3390);
DISPLAY 0.489362 (-4335 3390);
PAINT MONO (-4335 3390);
FORCEPROP 0 LASTPIN (-4275 3400) $PN DD37
R 1
J 2
(-4285 3390);
DISPLAY 0.489362 (-4285 3390);
PAINT MONO (-4285 3390);
FORCEPROP 0 LASTPIN (-4225 3400) $PN DD39
R 1
J 2
(-4235 3390);
DISPLAY 0.489362 (-4235 3390);
PAINT MONO (-4235 3390);
FORCEPROP 0 LASTPIN (-4175 3400) $PN DD40
R 1
J 2
(-4185 3390);
DISPLAY 0.489362 (-4185 3390);
PAINT MONO (-4185 3390);
FORCEPROP 0 LASTPIN (-4125 3400) $PN DD41
R 1
J 2
(-4135 3390);
DISPLAY 0.489362 (-4135 3390);
PAINT MONO (-4135 3390);
FORCEPROP 0 LASTPIN (-4075 3400) $PN DD43
R 1
J 2
(-4085 3390);
DISPLAY 0.489362 (-4085 3390);
PAINT MONO (-4085 3390);
FORCEPROP 0 LASTPIN (-4025 3400) $PN DD44
R 1
J 2
(-4035 3390);
DISPLAY 0.489362 (-4035 3390);
PAINT MONO (-4035 3390);
FORCEPROP 0 LASTPIN (-3975 3400) $PN DD46
R 1
J 2
(-3985 3390);
DISPLAY 0.489362 (-3985 3390);
PAINT MONO (-3985 3390);
FORCEPROP 0 LASTPIN (-3925 3400) $PN DD47
R 1
J 2
(-3935 3390);
DISPLAY 0.489362 (-3935 3390);
PAINT MONO (-3935 3390);
FORCEPROP 0 LASTPIN (-3875 3400) $PN DD49
R 1
J 2
(-3885 3390);
DISPLAY 0.489362 (-3885 3390);
PAINT MONO (-3885 3390);
FORCEPROP 0 LASTPIN (-3825 3400) $PN DD50
R 1
J 2
(-3835 3390);
DISPLAY 0.489362 (-3835 3390);
PAINT MONO (-3835 3390);
FORCEPROP 0 LASTPIN (-3775 3400) $PN DD52
R 1
J 2
(-3785 3390);
DISPLAY 0.489362 (-3785 3390);
PAINT MONO (-3785 3390);
FORCEPROP 0 LASTPIN (-3725 3400) $PN DD53
R 1
J 2
(-3735 3390);
DISPLAY 0.489362 (-3735 3390);
PAINT MONO (-3735 3390);
FORCEPROP 0 LASTPIN (-3675 3400) $PN DD57
R 1
J 2
(-3685 3390);
DISPLAY 0.489362 (-3685 3390);
PAINT MONO (-3685 3390);
FORCEPROP 0 LASTPIN (-3625 3400) $PN DD59
R 1
J 2
(-3635 3390);
DISPLAY 0.489362 (-3635 3390);
PAINT MONO (-3635 3390);
FORCEPROP 0 LASTPIN (-3575 3400) $PN DD61
R 1
J 2
(-3585 3390);
DISPLAY 0.489362 (-3585 3390);
PAINT MONO (-3585 3390);
FORCEPROP 0 LASTPIN (-3525 3400) $PN DD64
R 1
J 2
(-3535 3390);
DISPLAY 0.489362 (-3535 3390);
PAINT MONO (-3535 3390);
FORCEPROP 0 LASTPIN (-3475 3400) $PN DD66
R 1
J 2
(-3485 3390);
DISPLAY 0.489362 (-3485 3390);
PAINT MONO (-3485 3390);
FORCEPROP 0 LASTPIN (-3425 3400) $PN DD68
R 1
J 2
(-3435 3390);
DISPLAY 0.489362 (-3435 3390);
PAINT MONO (-3435 3390);
FORCEPROP 0 LASTPIN (-3375 3400) $PN DD71
R 1
J 2
(-3385 3390);
DISPLAY 0.489362 (-3385 3390);
PAINT MONO (-3385 3390);
FORCEPROP 0 LASTPIN (-3325 3400) $PN DD73
R 1
J 2
(-3335 3390);
DISPLAY 0.489362 (-3335 3390);
PAINT MONO (-3335 3390);
FORCEPROP 0 LASTPIN (-3275 3400) $PN DE1
R 1
J 2
(-3285 3390);
DISPLAY 0.489362 (-3285 3390);
PAINT MONO (-3285 3390);
FORCEPROP 0 LASTPIN (-3225 3400) $PN DE6
R 1
J 2
(-3235 3390);
DISPLAY 0.489362 (-3235 3390);
PAINT MONO (-3235 3390);
FORCEPROP 0 LASTPIN (-3175 3400) $PN DE8
R 1
J 2
(-3185 3390);
DISPLAY 0.489362 (-3185 3390);
PAINT MONO (-3185 3390);
FORCEPROP 0 LASTPIN (-3125 3400) $PN DE13
R 1
J 2
(-3135 3390);
DISPLAY 0.489362 (-3135 3390);
PAINT MONO (-3135 3390);
FORCEPROP 0 LASTPIN (-3075 3400) $PN DE15
R 1
J 2
(-3085 3390);
DISPLAY 0.489362 (-3085 3390);
PAINT MONO (-3085 3390);
FORCEPROP 0 LASTPIN (-3025 3400) $PN DE20
R 1
J 2
(-3035 3390);
DISPLAY 0.489362 (-3035 3390);
PAINT MONO (-3035 3390);
FORCEPROP 0 LASTPIN (-2975 3400) $PN DE23
R 1
J 2
(-2985 3390);
DISPLAY 0.489362 (-2985 3390);
PAINT MONO (-2985 3390);
FORCEPROP 0 LASTPIN (-2925 3400) $PN DE26
R 1
J 2
(-2935 3390);
DISPLAY 0.489362 (-2935 3390);
PAINT MONO (-2935 3390);
FORCEPROP 0 LASTPIN (-2875 3400) $PN DE29
R 1
J 2
(-2885 3390);
DISPLAY 0.489362 (-2885 3390);
PAINT MONO (-2885 3390);
FORCEPROP 0 LASTPIN (-2825 3400) $PN DE33
R 1
J 2
(-2835 3390);
DISPLAY 0.489362 (-2835 3390);
PAINT MONO (-2835 3390);
FORCEPROP 0 LASTPIN (-2775 3400) $PN DE56
R 1
J 2
(-2785 3390);
DISPLAY 0.489362 (-2785 3390);
PAINT MONO (-2785 3390);
FORCEPROP 0 LASTPIN (-2725 3400) $PN DE61
R 1
J 2
(-2735 3390);
DISPLAY 0.489362 (-2735 3390);
PAINT MONO (-2735 3390);
FORCEPROP 0 LASTPIN (-2675 3400) $PN DE63
R 1
J 2
(-2685 3390);
DISPLAY 0.489362 (-2685 3390);
PAINT MONO (-2685 3390);
FORCEPROP 0 LASTPIN (-2625 3400) $PN DE68
R 1
J 2
(-2635 3390);
DISPLAY 0.489362 (-2635 3390);
PAINT MONO (-2635 3390);
FORCEPROP 0 LASTPIN (-2575 3400) $PN DE70
R 1
J 2
(-2585 3390);
DISPLAY 0.489362 (-2585 3390);
PAINT MONO (-2585 3390);
FORCEPROP 0 LASTPIN (-2525 3400) $PN DE75
R 1
J 2
(-2535 3390);
DISPLAY 0.489362 (-2535 3390);
PAINT MONO (-2535 3390);
FORCEPROP 0 LASTPIN (-2475 3400) $PN DF3
R 1
J 2
(-2485 3390);
DISPLAY 0.489362 (-2485 3390);
PAINT MONO (-2485 3390);
FORCEPROP 0 LASTPIN (-2425 3400) $PN DF4
R 1
J 2
(-2435 3390);
DISPLAY 0.489362 (-2435 3390);
PAINT MONO (-2435 3390);
FORCEPROP 0 LASTPIN (-2375 3400) $PN DF5
R 1
J 2
(-2385 3390);
DISPLAY 0.489362 (-2385 3390);
PAINT MONO (-2385 3390);
FORCEPROP 0 LASTPIN (-2325 3400) $PN DF6
R 1
J 2
(-2335 3390);
DISPLAY 0.489362 (-2335 3390);
PAINT MONO (-2335 3390);
FORCEPROP 0 LASTPIN (-2275 3400) $PN DF8
R 1
J 2
(-2285 3390);
DISPLAY 0.489362 (-2285 3390);
PAINT MONO (-2285 3390);
FORCEPROP 0 LASTPIN (-2225 3400) $PN DF10
R 1
J 2
(-2235 3390);
DISPLAY 0.489362 (-2235 3390);
PAINT MONO (-2235 3390);
FORCEPROP 0 LASTPIN (-2175 3400) $PN DF11
R 1
J 2
(-2185 3390);
DISPLAY 0.489362 (-2185 3390);
PAINT MONO (-2185 3390);
FORCEPROP 0 LASTPIN (-2125 3400) $PN DF12
R 1
J 2
(-2135 3390);
DISPLAY 0.489362 (-2135 3390);
PAINT MONO (-2135 3390);
FORCEPROP 0 LASTPIN (-2075 3400) $PN DF13
R 1
J 2
(-2085 3390);
DISPLAY 0.489362 (-2085 3390);
PAINT MONO (-2085 3390);
FORCEPROP 0 LASTPIN (-2025 3400) $PN DF15
R 1
J 2
(-2035 3390);
DISPLAY 0.489362 (-2035 3390);
PAINT MONO (-2035 3390);
FORCEPROP 0 LASTPIN (-1975 3400) $PN DF17
R 1
J 2
(-1985 3390);
DISPLAY 0.489362 (-1985 3390);
PAINT MONO (-1985 3390);
FORCEPROP 0 LASTPIN (-1925 3400) $PN DF18
R 1
J 2
(-1935 3390);
DISPLAY 0.489362 (-1935 3390);
PAINT MONO (-1935 3390);
FORCEPROP 0 LASTPIN (-1875 3400) $PN DF19
R 1
J 2
(-1885 3390);
DISPLAY 0.489362 (-1885 3390);
PAINT MONO (-1885 3390);
FORCEPROP 0 LASTPIN (-7775 4500) $PN DF20
R 1
J 0
(-7785 4510);
DISPLAY 0.489362 (-7785 4510);
PAINT MONO (-7785 4510);
FORCEPROP 0 LASTPIN (-7725 4500) $PN DF22
R 1
J 0
(-7735 4510);
DISPLAY 0.489362 (-7735 4510);
PAINT MONO (-7735 4510);
FORCEPROP 0 LASTPIN (-7675 4500) $PN DF23
R 1
J 0
(-7685 4510);
DISPLAY 0.489362 (-7685 4510);
PAINT MONO (-7685 4510);
FORCEPROP 0 LASTPIN (-7625 4500) $PN DF26
R 1
J 0
(-7635 4510);
DISPLAY 0.489362 (-7635 4510);
PAINT MONO (-7635 4510);
FORCEPROP 0 LASTPIN (-7575 4500) $PN DF29
R 1
J 0
(-7585 4510);
DISPLAY 0.489362 (-7585 4510);
PAINT MONO (-7585 4510);
FORCEPROP 0 LASTPIN (-7525 4500) $PN DF32
R 1
J 0
(-7535 4510);
DISPLAY 0.489362 (-7535 4510);
PAINT MONO (-7535 4510);
FORCEPROP 0 LASTPIN (-7475 4500) $PN DF35
R 1
J 0
(-7485 4510);
DISPLAY 0.489362 (-7485 4510);
PAINT MONO (-7485 4510);
FORCEPROP 0 LASTPIN (-7425 4500) $PN DF37
R 1
J 0
(-7435 4510);
DISPLAY 0.489362 (-7435 4510);
PAINT MONO (-7435 4510);
FORCEPROP 0 LASTPIN (-7375 4500) $PN DF39
R 1
J 0
(-7385 4510);
DISPLAY 0.489362 (-7385 4510);
PAINT MONO (-7385 4510);
FORCEPROP 0 LASTPIN (-7325 4500) $PN DF42
R 1
J 0
(-7335 4510);
DISPLAY 0.489362 (-7335 4510);
PAINT MONO (-7335 4510);
FORCEPROP 0 LASTPIN (-7275 4500) $PN DF43
R 1
J 0
(-7285 4510);
DISPLAY 0.489362 (-7285 4510);
PAINT MONO (-7285 4510);
FORCEPROP 0 LASTPIN (-7225 4500) $PN DF44
R 1
J 0
(-7235 4510);
DISPLAY 0.489362 (-7235 4510);
PAINT MONO (-7235 4510);
FORCEPROP 0 LASTPIN (-7175 4500) $PN DF45
R 1
J 0
(-7185 4510);
DISPLAY 0.489362 (-7185 4510);
PAINT MONO (-7185 4510);
FORCEPROP 0 LASTPIN (-7125 4500) $PN DF46
R 1
J 0
(-7135 4510);
DISPLAY 0.489362 (-7135 4510);
PAINT MONO (-7135 4510);
FORCEPROP 0 LASTPIN (-7075 4500) $PN DF47
R 1
J 0
(-7085 4510);
DISPLAY 0.489362 (-7085 4510);
PAINT MONO (-7085 4510);
FORCEPROP 0 LASTPIN (-7025 4500) $PN DF48
R 1
J 0
(-7035 4510);
DISPLAY 0.489362 (-7035 4510);
PAINT MONO (-7035 4510);
FORCEPROP 0 LASTPIN (-6975 4500) $PN DF49
R 1
J 0
(-6985 4510);
DISPLAY 0.489362 (-6985 4510);
PAINT MONO (-6985 4510);
FORCEPROP 0 LASTPIN (-6925 4500) $PN DF50
R 1
J 0
(-6935 4510);
DISPLAY 0.489362 (-6935 4510);
PAINT MONO (-6935 4510);
FORCEPROP 0 LASTPIN (-6875 4500) $PN DF51
R 1
J 0
(-6885 4510);
DISPLAY 0.489362 (-6885 4510);
PAINT MONO (-6885 4510);
FORCEPROP 0 LASTPIN (-6825 4500) $PN DF52
R 1
J 0
(-6835 4510);
DISPLAY 0.489362 (-6835 4510);
PAINT MONO (-6835 4510);
FORCEPROP 0 LASTPIN (-6775 4500) $PN DF53
R 1
J 0
(-6785 4510);
DISPLAY 0.489362 (-6785 4510);
PAINT MONO (-6785 4510);
FORCEPROP 0 LASTPIN (-6725 4500) $PN DF54
R 1
J 0
(-6735 4510);
DISPLAY 0.489362 (-6735 4510);
PAINT MONO (-6735 4510);
FORCEPROP 0 LASTPIN (-6675 4500) $PN DF56
R 1
J 0
(-6685 4510);
DISPLAY 0.489362 (-6685 4510);
PAINT MONO (-6685 4510);
FORCEPROP 0 LASTPIN (-6625 4500) $PN DF57
R 1
J 0
(-6635 4510);
DISPLAY 0.489362 (-6635 4510);
PAINT MONO (-6635 4510);
FORCEPROP 0 LASTPIN (-6575 4500) $PN DF58
R 1
J 0
(-6585 4510);
DISPLAY 0.489362 (-6585 4510);
PAINT MONO (-6585 4510);
FORCEPROP 0 LASTPIN (-6525 4500) $PN DF59
R 1
J 0
(-6535 4510);
DISPLAY 0.489362 (-6535 4510);
PAINT MONO (-6535 4510);
FORCEPROP 0 LASTPIN (-6475 4500) $PN DF61
R 1
J 0
(-6485 4510);
DISPLAY 0.489362 (-6485 4510);
PAINT MONO (-6485 4510);
FORCEPROP 0 LASTPIN (-6425 4500) $PN DF63
R 1
J 0
(-6435 4510);
DISPLAY 0.489362 (-6435 4510);
PAINT MONO (-6435 4510);
FORCEPROP 0 LASTPIN (-6375 4500) $PN DF64
R 1
J 0
(-6385 4510);
DISPLAY 0.489362 (-6385 4510);
PAINT MONO (-6385 4510);
FORCEPROP 0 LASTPIN (-6325 4500) $PN DF65
R 1
J 0
(-6335 4510);
DISPLAY 0.489362 (-6335 4510);
PAINT MONO (-6335 4510);
FORCEPROP 0 LASTPIN (-6275 4500) $PN DF66
R 1
J 0
(-6285 4510);
DISPLAY 0.489362 (-6285 4510);
PAINT MONO (-6285 4510);
FORCEPROP 0 LASTPIN (-6225 4500) $PN DF68
R 1
J 0
(-6235 4510);
DISPLAY 0.489362 (-6235 4510);
PAINT MONO (-6235 4510);
FORCEPROP 0 LASTPIN (-6175 4500) $PN DF70
R 1
J 0
(-6185 4510);
DISPLAY 0.489362 (-6185 4510);
PAINT MONO (-6185 4510);
FORCEPROP 0 LASTPIN (-6125 4500) $PN DF71
R 1
J 0
(-6135 4510);
DISPLAY 0.489362 (-6135 4510);
PAINT MONO (-6135 4510);
FORCEPROP 0 LASTPIN (-6075 4500) $PN DF72
R 1
J 0
(-6085 4510);
DISPLAY 0.489362 (-6085 4510);
PAINT MONO (-6085 4510);
FORCEPROP 0 LASTPIN (-6025 4500) $PN DF73
R 1
J 0
(-6035 4510);
DISPLAY 0.489362 (-6035 4510);
PAINT MONO (-6035 4510);
FORCEPROP 0 LASTPIN (-5975 4500) $PN DG1
R 1
J 0
(-5985 4510);
DISPLAY 0.489362 (-5985 4510);
PAINT MONO (-5985 4510);
FORCEPROP 0 LASTPIN (-5925 4500) $PN DG2
R 1
J 0
(-5935 4510);
DISPLAY 0.489362 (-5935 4510);
PAINT MONO (-5935 4510);
FORCEPROP 0 LASTPIN (-5875 4500) $PN DG6
R 1
J 0
(-5885 4510);
DISPLAY 0.489362 (-5885 4510);
PAINT MONO (-5885 4510);
FORCEPROP 0 LASTPIN (-5825 4500) $PN DG7
R 1
J 0
(-5835 4510);
DISPLAY 0.489362 (-5835 4510);
PAINT MONO (-5835 4510);
FORCEPROP 0 LASTPIN (-5775 4500) $PN DG8
R 1
J 0
(-5785 4510);
DISPLAY 0.489362 (-5785 4510);
PAINT MONO (-5785 4510);
FORCEPROP 0 LASTPIN (-5725 4500) $PN DG9
R 1
J 0
(-5735 4510);
DISPLAY 0.489362 (-5735 4510);
PAINT MONO (-5735 4510);
FORCEPROP 0 LASTPIN (-5675 4500) $PN DG13
R 1
J 0
(-5685 4510);
DISPLAY 0.489362 (-5685 4510);
PAINT MONO (-5685 4510);
FORCEPROP 0 LASTPIN (-5625 4500) $PN DG14
R 1
J 0
(-5635 4510);
DISPLAY 0.489362 (-5635 4510);
PAINT MONO (-5635 4510);
FORCEPROP 0 LASTPIN (-5575 4500) $PN DG15
R 1
J 0
(-5585 4510);
DISPLAY 0.489362 (-5585 4510);
PAINT MONO (-5585 4510);
FORCEPROP 0 LASTPIN (-5525 4500) $PN DG16
R 1
J 0
(-5535 4510);
DISPLAY 0.489362 (-5535 4510);
PAINT MONO (-5535 4510);
FORCEPROP 0 LASTPIN (-5475 4500) $PN DG18
R 1
J 0
(-5485 4510);
DISPLAY 0.489362 (-5485 4510);
PAINT MONO (-5485 4510);
FORCEPROP 0 LASTPIN (-5425 4500) $PN DG20
R 1
J 0
(-5435 4510);
DISPLAY 0.489362 (-5435 4510);
PAINT MONO (-5435 4510);
FORCEPROP 0 LASTPIN (-5375 4500) $PN DG21
R 1
J 0
(-5385 4510);
DISPLAY 0.489362 (-5385 4510);
PAINT MONO (-5385 4510);
FORCEPROP 0 LASTPIN (-5325 4500) $PN DG24
R 1
J 0
(-5335 4510);
DISPLAY 0.489362 (-5335 4510);
PAINT MONO (-5335 4510);
FORCEPROP 0 LASTPIN (-5275 4500) $PN DG27
R 1
J 0
(-5285 4510);
DISPLAY 0.489362 (-5285 4510);
PAINT MONO (-5285 4510);
FORCEPROP 0 LASTPIN (-5225 4500) $PN DG30
R 1
J 0
(-5235 4510);
DISPLAY 0.489362 (-5235 4510);
PAINT MONO (-5235 4510);
FORCEPROP 0 LASTPIN (-5175 4500) $PN DG33
R 1
J 0
(-5185 4510);
DISPLAY 0.489362 (-5185 4510);
PAINT MONO (-5185 4510);
FORCEPROP 0 LASTPIN (-5125 4500) $PN DG41
R 1
J 0
(-5135 4510);
DISPLAY 0.489362 (-5135 4510);
PAINT MONO (-5135 4510);
FORCEPROP 0 LASTPIN (-5075 4500) $PN DG43
R 1
J 0
(-5085 4510);
DISPLAY 0.489362 (-5085 4510);
PAINT MONO (-5085 4510);
FORCEPROP 0 LASTPIN (-5025 4500) $PN DG46
R 1
J 0
(-5035 4510);
DISPLAY 0.489362 (-5035 4510);
PAINT MONO (-5035 4510);
FORCEPROP 0 LASTPIN (-4975 4500) $PN DG49
R 1
J 0
(-4985 4510);
DISPLAY 0.489362 (-4985 4510);
PAINT MONO (-4985 4510);
FORCEPROP 0 LASTPIN (-4925 4500) $PN DG52
R 1
J 0
(-4935 4510);
DISPLAY 0.489362 (-4935 4510);
PAINT MONO (-4935 4510);
FORCEPROP 0 LASTPIN (-4875 4500) $PN DG55
R 1
J 0
(-4885 4510);
DISPLAY 0.489362 (-4885 4510);
PAINT MONO (-4885 4510);
FORCEPROP 0 LASTPIN (-4825 4500) $PN DG56
R 1
J 0
(-4835 4510);
DISPLAY 0.489362 (-4835 4510);
PAINT MONO (-4835 4510);
FORCEPROP 0 LASTPIN (-4775 4500) $PN DG59
R 1
J 0
(-4785 4510);
DISPLAY 0.489362 (-4785 4510);
PAINT MONO (-4785 4510);
FORCEPROP 0 LASTPIN (-4725 4500) $PN DG60
R 1
J 0
(-4735 4510);
DISPLAY 0.489362 (-4735 4510);
PAINT MONO (-4735 4510);
FORCEPROP 0 LASTPIN (-4675 4500) $PN DG61
R 1
J 0
(-4685 4510);
DISPLAY 0.489362 (-4685 4510);
PAINT MONO (-4685 4510);
FORCEPROP 0 LASTPIN (-4625 4500) $PN DG62
R 1
J 0
(-4635 4510);
DISPLAY 0.489362 (-4635 4510);
PAINT MONO (-4635 4510);
FORCEPROP 0 LASTPIN (-4575 4500) $PN DG63
R 1
J 0
(-4585 4510);
DISPLAY 0.489362 (-4585 4510);
PAINT MONO (-4585 4510);
FORCEPROP 0 LASTPIN (-4525 4500) $PN DG65
R 1
J 0
(-4535 4510);
DISPLAY 0.489362 (-4535 4510);
PAINT MONO (-4535 4510);
FORCEPROP 0 LASTPIN (-4475 4500) $PN DG66
R 1
J 0
(-4485 4510);
DISPLAY 0.489362 (-4485 4510);
PAINT MONO (-4485 4510);
FORCEPROP 0 LASTPIN (-4425 4500) $PN DG67
R 1
J 0
(-4435 4510);
DISPLAY 0.489362 (-4435 4510);
PAINT MONO (-4435 4510);
FORCEPROP 0 LASTPIN (-4375 4500) $PN DG68
R 1
J 0
(-4385 4510);
DISPLAY 0.489362 (-4385 4510);
PAINT MONO (-4385 4510);
FORCEPROP 0 LASTPIN (-4325 4500) $PN DG69
R 1
J 0
(-4335 4510);
DISPLAY 0.489362 (-4335 4510);
PAINT MONO (-4335 4510);
FORCEPROP 0 LASTPIN (-4275 4500) $PN DG70
R 1
J 0
(-4285 4510);
DISPLAY 0.489362 (-4285 4510);
PAINT MONO (-4285 4510);
FORCEPROP 0 LASTPIN (-4225 4500) $PN DG74
R 1
J 0
(-4235 4510);
DISPLAY 0.489362 (-4235 4510);
PAINT MONO (-4235 4510);
FORCEPROP 0 LASTPIN (-4175 4500) $PN DG75
R 1
J 0
(-4185 4510);
DISPLAY 0.489362 (-4185 4510);
PAINT MONO (-4185 4510);
FORCEPROP 0 LASTPIN (-4125 4500) $PN DH5
R 1
J 0
(-4135 4510);
DISPLAY 0.489362 (-4135 4510);
PAINT MONO (-4135 4510);
FORCEPROP 0 LASTPIN (-4075 4500) $PN DH11
R 1
J 0
(-4085 4510);
DISPLAY 0.489362 (-4085 4510);
PAINT MONO (-4085 4510);
FORCEPROP 0 LASTPIN (-4025 4500) $PN DH18
R 1
J 0
(-4035 4510);
DISPLAY 0.489362 (-4035 4510);
PAINT MONO (-4035 4510);
FORCEPROP 0 LASTPIN (-3975 4500) $PN DH37
R 1
J 0
(-3985 4510);
DISPLAY 0.489362 (-3985 4510);
PAINT MONO (-3985 4510);
FORCEPROP 0 LASTPIN (-3925 4500) $PN DH39
R 1
J 0
(-3935 4510);
DISPLAY 0.489362 (-3935 4510);
PAINT MONO (-3935 4510);
FORCEPROP 0 LASTPIN (-3875 4500) $PN DH43
R 1
J 0
(-3885 4510);
DISPLAY 0.489362 (-3885 4510);
PAINT MONO (-3885 4510);
FORCEPROP 0 LASTPIN (-3825 4500) $PN DH46
R 1
J 0
(-3835 4510);
DISPLAY 0.489362 (-3835 4510);
PAINT MONO (-3835 4510);
FORCEPROP 0 LASTPIN (-3775 4500) $PN DH49
R 1
J 0
(-3785 4510);
DISPLAY 0.489362 (-3785 4510);
PAINT MONO (-3785 4510);
FORCEPROP 0 LASTPIN (-3725 4500) $PN DH52
R 1
J 0
(-3735 4510);
DISPLAY 0.489362 (-3735 4510);
PAINT MONO (-3735 4510);
FORCEPROP 0 LASTPIN (-3675 4500) $PN DH55
R 1
J 0
(-3685 4510);
DISPLAY 0.489362 (-3685 4510);
PAINT MONO (-3685 4510);
FORCEPROP 0 LASTPIN (-3625 4500) $PN DH59
R 1
J 0
(-3635 4510);
DISPLAY 0.489362 (-3635 4510);
PAINT MONO (-3635 4510);
FORCEPROP 0 LASTPIN (-3575 4500) $PN DH61
R 1
J 0
(-3585 4510);
DISPLAY 0.489362 (-3585 4510);
PAINT MONO (-3585 4510);
FORCEPROP 0 LASTPIN (-3525 4500) $PN DH63
R 1
J 0
(-3535 4510);
DISPLAY 0.489362 (-3535 4510);
PAINT MONO (-3535 4510);
FORCEPROP 0 LASTPIN (-3475 4500) $PN DH64
R 1
J 0
(-3485 4510);
DISPLAY 0.489362 (-3485 4510);
PAINT MONO (-3485 4510);
FORCEPROP 0 LASTPIN (-3425 4500) $PN DH66
R 1
J 0
(-3435 4510);
DISPLAY 0.489362 (-3435 4510);
PAINT MONO (-3435 4510);
FORCEPROP 0 LASTPIN (-3375 4500) $PN DH68
R 1
J 0
(-3385 4510);
DISPLAY 0.489362 (-3385 4510);
PAINT MONO (-3385 4510);
FORCEPROP 0 LASTPIN (-3325 4500) $PN DH70
R 1
J 0
(-3335 4510);
DISPLAY 0.489362 (-3335 4510);
PAINT MONO (-3335 4510);
FORCEPROP 0 LASTPIN (-3275 4500) $PN DJ7
R 1
J 0
(-3285 4510);
DISPLAY 0.489362 (-3285 4510);
PAINT MONO (-3285 4510);
FORCEPROP 0 LASTPIN (-3225 4500) $PN DJ15
R 1
J 0
(-3235 4510);
DISPLAY 0.489362 (-3235 4510);
PAINT MONO (-3235 4510);
FORCEPROP 0 LASTPIN (-3175 4500) $PN DJ19
R 1
J 0
(-3185 4510);
DISPLAY 0.489362 (-3185 4510);
PAINT MONO (-3185 4510);
FORCEPROP 0 LASTPIN (-3125 4500) $PN DJ43
R 1
J 0
(-3135 4510);
DISPLAY 0.489362 (-3135 4510);
PAINT MONO (-3135 4510);
FORCEPROP 0 LASTPIN (-3075 4500) $PN DJ49
R 1
J 0
(-3085 4510);
DISPLAY 0.489362 (-3085 4510);
PAINT MONO (-3085 4510);
FORCEPROP 0 LASTPIN (-3025 4500) $PN DJ59
R 1
J 0
(-3035 4510);
DISPLAY 0.489362 (-3035 4510);
PAINT MONO (-3035 4510);
FORCEPROP 0 LASTPIN (-2975 4500) $PN DJ61
R 1
J 0
(-2985 4510);
DISPLAY 0.489362 (-2985 4510);
PAINT MONO (-2985 4510);
FORCEPROP 0 LASTPIN (-2925 4500) $PN DJ63
R 1
J 0
(-2935 4510);
DISPLAY 0.489362 (-2935 4510);
PAINT MONO (-2935 4510);
FORCEPROP 0 LASTPIN (-2875 4500) $PN DJ66
R 1
J 0
(-2885 4510);
DISPLAY 0.489362 (-2885 4510);
PAINT MONO (-2885 4510);
FORCEPROP 0 LASTPIN (-2825 4500) $PN DJ68
R 1
J 0
(-2835 4510);
DISPLAY 0.489362 (-2835 4510);
PAINT MONO (-2835 4510);
FORCEPROP 0 LASTPIN (-2775 4500) $PN DJ73
R 1
J 0
(-2785 4510);
DISPLAY 0.489362 (-2785 4510);
PAINT MONO (-2785 4510);
FORCEPROP 0 LASTPIN (-2725 4500) $PN K23
R 1
J 0
(-2735 4510);
DISPLAY 0.489362 (-2735 4510);
PAINT MONO (-2735 4510);
FORCEPROP 0 LASTPIN (-2675 4500) $PN K59
R 1
J 0
(-2685 4510);
DISPLAY 0.489362 (-2685 4510);
PAINT MONO (-2685 4510);
FORCEPROP 0 LASTPIN (-2625 4500) $PN P25
R 1
J 0
(-2635 4510);
DISPLAY 0.489362 (-2635 4510);
PAINT MONO (-2635 4510);
FORCEPROP 0 LASTPIN (-2575 4500) $PN P68
R 1
J 0
(-2585 4510);
DISPLAY 0.489362 (-2585 4510);
PAINT MONO (-2585 4510);
FORCEPROP 0 LASTPIN (-2525 4500) $PN V27
R 1
J 0
(-2535 4510);
DISPLAY 0.489362 (-2535 4510);
PAINT MONO (-2535 4510);
FORCEPROP 0 LASTPIN (-2475 4500) $PN V68
R 1
J 0
(-2485 4510);
DISPLAY 0.489362 (-2485 4510);
PAINT MONO (-2485 4510);
FORCEPROP 2 LAST PART_TYPE SMLF
R 1
J 0
(-8300 3550);
DISPLAY 1.021277 (-8300 3550);
FORCEPROP 1 LAST MATERIAL IO
R 1
J 0
(-7907 3555);
DISPLAY 0.489362 (-7907 3555);
PAINT SKYBLUE (-7907 3555);
FORCEPROP 2 LAST VALUE SOCKET6096_13568-001
R 1
J 0
(-7975 3550);
DISPLAY 0.489362 (-7975 3550);
PAINT SKYBLUE (-7975 3550);
FORCEPROP 1 LAST PART_NUMBER DGA^6000030
R 1
J 0
(-8034 3555);
DISPLAY 0.489362 (-8034 3555);
PAINT SKYBLUE (-8034 3555);
FORCEPROP 2 LAST CDS_LIB pure_quanta
J 0
(-4525 3950);
DISPLAY INVISIBLE (-4525 3950);
FORCEPROP 1 LAST CDS_LMAN_SYM_OUTLINE -400,3350,400,-3350
R 1
J 0
(-4525 3950);
DISPLAY 0.468085 (-4525 3950);
PAINT GREEN (-4525 3950);
DISPLAY INVISIBLE (-4525 3950);
FORCEPROP 1 LAST NEEDS_NO_SIZE TRUE
R 1
J 0
(-4525 3950);
DISPLAY 0.723404 (-4525 3950);
PAINT GREEN (-4525 3950);
DISPLAY INVISIBLE (-4525 3950);
FORCEPROP 1 LAST PATH I3
R 1
J 0
(-4525 3950);
DISPLAY 0.723404 (-4525 3950);
PAINT GREEN (-4525 3950);
DISPLAY INVISIBLE (-4525 3950);
FORCEADD QUANTA_TITLE_BLOCK_C..1
(-100 100);
FORCEPROP 0 LAST CDS_CON_LAST_MODIFIED Fri Mar 11 14:52:43 2022
J 0
(-1985 115);
DISPLAY INVISIBLE (-1985 115);
FORCEPROP 1 LAST CUSTOM_TXT_CDS <CON_LAST_MODIFIED>
J 0
(-1985 115);
DISPLAY 0.978723 (-1985 115);
FORCEPROP 2 LAST CUSTOM_TXT_CDS <XR_PAGE_TITLE>
J 0
(-7990 5350);
DISPLAY 0.638298 (-7990 5350);
PAINT PINK (-7990 5350);
DISPLAY INVISIBLE (-7990 5350);
FORCEPROP 1 LAST CUSTOM_TXT_CDS <NAME_2>
J 0
(-3275 150);
FORCEPROP 1 LAST CUSTOM_TXT_CDS <NAME_1>
J 0
(-3275 275);
FORCEPROP 1 LAST CUSTOM_TXT_CDS <Q_NUMBER>
J 0
(-1503 203);
DISPLAY 1.212766 (-1503 203);
FORCEPROP 1 LAST CUSTOM_TXT_CDS <Q_PROJ>
J 0
(-2482 202);
DISPLAY 1.212766 (-2482 202);
FORCEPROP 1 LAST CUSTOM_TXT_CDS <Q_REV>
J 0
(-284 203);
DISPLAY 1.212766 (-284 203);
FORCEPROP 1 LAST CUSTOM_TXT_CDS <CON_PAGE_NUM> OF <CON_TOTAL_PAGES>
J 0
(-546 118);
DISPLAY 0.978723 (-546 118);
FORCEPROP 1 LAST Q_TITLE CPU1 VSS 3/3
J 0
(-9400 150);
DISPLAY 2.446809 (-9400 150);
PAINT GREEN (-9400 150);
FORCEPROP 1 LAST Q_DEPT BU9
J 1
(-3863 149);
DISPLAY 1.957447 (-3863 149);
PAINT GREEN (-3863 149);
FORCEPROP 2 LAST CDS_LIB pure_quanta
J 0
(-100 100);
DISPLAY INVISIBLE (-100 100);
FORCEPROP 1 LAST CDS_LMAN_SYM_OUTLINE -9475,6775,100,-125
J 0
(-100 100);
DISPLAY 0.468085 (-100 100);
PAINT GREEN (-100 100);
DISPLAY INVISIBLE (-100 100);
FORCEPROP 2 LAST PAGE_BORDER TRUE
J 0
(-7990 5350);
DISPLAY 0.638298 (-7990 5350);
PAINT PINK (-7990 5350);
DISPLAY INVISIBLE (-7990 5350);
FORCEPROP 1 LAST COMMENT_BODY TRUE
J 0
(-88 87);
DISPLAY 0.978723 (-88 87);
PAINT GREEN (-88 87);
DISPLAY INVISIBLE (-88 87);
FORCEPROP 2 LAST CDS_XR_PAGE_TITLE CR-60 : @T6G_MB_LIB.T6G(SCH_1):PAGE60
J 0
(-7990 5350);
DISPLAY 0.638298 (-7990 5350);
PAINT PINK (-7990 5350);
DISPLAY INVISIBLE (-7990 5350);
WIRE 16 -1 (-7775 3400)(-7775 3225);
WIRE 16 -1 (-7775 3225)(-7725 3225);
WIRE 16 -1 (-7725 3225)(-7675 3225);
WIRE 16 -1 (-7725 3225)(-7725 3400);
WIRE 16 -1 (-7675 3400)(-7675 3225);
WIRE 16 -1 (-7675 3225)(-7625 3225);
WIRE 16 -1 (-7625 3225)(-7625 3400);
WIRE 16 -1 (-7625 3225)(-7575 3225);
WIRE 16 -1 (-7575 3225)(-7575 3400);
WIRE 16 -1 (-7575 3225)(-7525 3225);
WIRE 16 -1 (-7525 3400)(-7525 3225);
WIRE 16 -1 (-7525 3225)(-7475 3225);
WIRE 16 -1 (-7475 3225)(-7475 3400);
WIRE 16 -1 (-7475 3225)(-7425 3225);
WIRE 16 -1 (-7425 3225)(-7375 3225);
WIRE 16 -1 (-7425 3225)(-7425 3400);
WIRE 16 -1 (-7375 3400)(-7375 3225);
WIRE 16 -1 (-7375 3225)(-7325 3225);
WIRE 16 -1 (-7325 3225)(-7325 3400);
WIRE 16 -1 (-7325 3225)(-7275 3225);
WIRE 16 -1 (-7275 3400)(-7275 3225);
WIRE 16 -1 (-7275 3225)(-7225 3225);
WIRE 16 -1 (-7225 3225)(-7225 3400);
WIRE 16 -1 (-7225 3225)(-7175 3225);
WIRE 16 -1 (-7175 3225)(-7125 3225);
WIRE 16 -1 (-7175 3225)(-7175 3400);
WIRE 16 -1 (-7125 3400)(-7125 3225);
WIRE 16 -1 (-7125 3225)(-7075 3225);
WIRE 16 -1 (-7075 3225)(-7075 3400);
WIRE 16 -1 (-7075 3225)(-7025 3225);
WIRE 16 -1 (-7025 3400)(-7025 3225);
WIRE 16 -1 (-7025 3225)(-6975 3225);
WIRE 16 -1 (-6975 3225)(-6975 3400);
WIRE 16 -1 (-6975 3225)(-6925 3225);
WIRE 16 -1 (-6925 3225)(-6875 3225);
WIRE 16 -1 (-6925 3225)(-6925 3400);
WIRE 16 -1 (-6875 3400)(-6875 3225);
WIRE 16 -1 (-6875 3225)(-6825 3225);
WIRE 16 -1 (-6825 3225)(-6825 3400);
WIRE 16 -1 (-6825 3225)(-6775 3225);
WIRE 16 -1 (-6775 3400)(-6775 3225);
WIRE 16 -1 (-6775 3225)(-6725 3225);
WIRE 16 -1 (-6725 3225)(-6725 3400);
WIRE 16 -1 (-6725 3225)(-6675 3225);
WIRE 16 -1 (-6675 3225)(-6625 3225);
WIRE 16 -1 (-6675 3225)(-6675 3400);
WIRE 16 -1 (-6625 3400)(-6625 3225);
WIRE 16 -1 (-6625 3225)(-6575 3225);
WIRE 16 -1 (-6575 3225)(-6575 3400);
WIRE 16 -1 (-6575 3225)(-6525 3225);
WIRE 16 -1 (-6525 3400)(-6525 3225);
WIRE 16 -1 (-6525 3225)(-6475 3225);
WIRE 16 -1 (-6475 3400)(-6475 3225);
WIRE 16 -1 (-6475 3225)(-6425 3225);
WIRE 16 -1 (-6425 3225)(-6375 3225);
WIRE 16 -1 (-6425 3225)(-6425 3400);
WIRE 16 -1 (-6375 3400)(-6375 3225);
WIRE 16 -1 (-6375 3225)(-6325 3225);
WIRE 16 -1 (-6325 3225)(-6325 3400);
WIRE 16 -1 (-6325 3225)(-6275 3225);
WIRE 16 -1 (-6275 3225)(-6275 3400);
WIRE 16 -1 (-6275 3225)(-6225 3225);
WIRE 16 -1 (-6225 3400)(-6225 3225);
WIRE 16 -1 (-6225 3225)(-6175 3225);
WIRE 16 -1 (-6175 3225)(-6125 3225);
WIRE 16 -1 (-6175 3225)(-6175 3400);
WIRE 16 -1 (-6125 3400)(-6125 3225);
WIRE 16 -1 (-6125 3225)(-6075 3225);
WIRE 16 -1 (-6075 3225)(-6075 3400);
WIRE 16 -1 (-6075 3225)(-6025 3225);
WIRE 16 -1 (-6025 3225)(-6025 3400);
WIRE 16 -1 (-6025 3225)(-5975 3225);
WIRE 16 -1 (-5975 3400)(-5975 3225);
WIRE 16 -1 (-5975 3225)(-5925 3225);
WIRE 16 -1 (-5925 3225)(-5875 3225);
WIRE 16 -1 (-5925 3225)(-5925 3400);
WIRE 16 -1 (-5875 3400)(-5875 3225);
WIRE 16 -1 (-5875 3225)(-5825 3225);
WIRE 16 -1 (-5825 3225)(-5825 3400);
WIRE 16 -1 (-5825 3225)(-5775 3225);
WIRE 16 -1 (-5775 3225)(-5775 3400);
WIRE 16 -1 (-5775 3225)(-5725 3225);
WIRE 16 -1 (-5725 3400)(-5725 3225);
WIRE 16 -1 (-5725 3225)(-5675 3225);
WIRE 16 -1 (-5675 3225)(-5625 3225);
WIRE 16 -1 (-5675 3225)(-5675 3400);
WIRE 16 -1 (-5625 3400)(-5625 3225);
WIRE 16 -1 (-5625 3225)(-5575 3225);
WIRE 16 -1 (-5575 3225)(-5575 3400);
WIRE 16 -1 (-5575 3225)(-5525 3225);
WIRE 16 -1 (-5525 3225)(-5525 3400);
WIRE 16 -1 (-5525 3225)(-5475 3225);
WIRE 16 -1 (-5475 3400)(-5475 3225);
WIRE 16 -1 (-5475 3225)(-5425 3225);
WIRE 16 -1 (-5425 3225)(-5375 3225);
WIRE 16 -1 (-5425 3225)(-5425 3400);
WIRE 16 -1 (-5375 3225)(-5375 3400);
WIRE 16 -1 (-5375 3225)(-5325 3225);
WIRE 16 -1 (-5325 3400)(-5325 3225);
WIRE 16 -1 (-5325 3225)(-5275 3225);
WIRE 16 -1 (-5275 3225)(-5275 3400);
WIRE 16 -1 (-5275 3225)(-5225 3225);
WIRE 16 -1 (-5225 3400)(-5225 3225);
WIRE 16 -1 (-5225 3225)(-5175 3225);
WIRE 16 -1 (-5175 3225)(-5175 3400);
WIRE 16 -1 (-5175 3225)(-5125 3225);
WIRE 16 -1 (-5125 3225)(-5075 3225);
WIRE 16 -1 (-5125 3225)(-5125 3400);
WIRE 16 -1 (-5075 3400)(-5075 3225);
WIRE 16 -1 (-5075 3225)(-5025 3225);
WIRE 16 -1 (-5025 3225)(-5025 3400);
WIRE 16 -1 (-5025 3225)(-4975 3225);
WIRE 16 -1 (-4975 3400)(-4975 3225);
WIRE 16 -1 (-4975 3225)(-4925 3225);
WIRE 16 -1 (-4925 3225)(-4925 3400);
WIRE 16 -1 (-4925 3225)(-4875 3225);
WIRE 16 -1 (-4875 3225)(-4825 3225);
WIRE 16 -1 (-4875 3225)(-4875 3400);
WIRE 16 -1 (-4825 3400)(-4825 3225);
WIRE 16 -1 (-4825 3225)(-4775 3225);
WIRE 16 -1 (-4775 3225)(-4775 3400);
WIRE 16 -1 (-4775 3225)(-4725 3225);
WIRE 16 -1 (-4725 3400)(-4725 3225);
WIRE 16 -1 (-4725 3225)(-4675 3225);
WIRE 16 -1 (-4675 3225)(-4675 3400);
WIRE 16 -1 (-4675 3225)(-4625 3225);
WIRE 16 -1 (-4625 3225)(-4575 3225);
WIRE 16 -1 (-4625 3225)(-4625 3400);
WIRE 16 -1 (-4575 3400)(-4575 3225);
WIRE 16 -1 (-4575 3225)(-4525 3225);
WIRE 16 -1 (-4525 3225)(-4525 3400);
WIRE 16 -1 (-4525 3225)(-4475 3225);
WIRE 16 -1 (-4475 3400)(-4475 3225);
WIRE 16 -1 (-4475 3225)(-4425 3225);
WIRE 16 -1 (-4425 3225)(-4425 3400);
WIRE 16 -1 (-4425 3225)(-4375 3225);
WIRE 16 -1 (-4375 3225)(-4325 3225);
WIRE 16 -1 (-4375 3225)(-4375 3400);
WIRE 16 -1 (-4325 3400)(-4325 3225);
WIRE 16 -1 (-4325 3225)(-4275 3225);
WIRE 16 -1 (-4275 3225)(-4275 3400);
WIRE 16 -1 (-4275 3225)(-4225 3225);
WIRE 16 -1 (-4225 3225)(-4225 3400);
WIRE 16 -1 (-4225 3225)(-4175 3225);
WIRE 16 -1 (-4175 3400)(-4175 3225);
WIRE 16 -1 (-4175 3225)(-4125 3225);
WIRE 16 -1 (-4125 3225)(-4075 3225);
WIRE 16 -1 (-4125 3225)(-4125 3400);
WIRE 16 -1 (-4075 3400)(-4075 3225);
WIRE 16 -1 (-4075 3225)(-4025 3225);
WIRE 16 -1 (-4025 3225)(-4025 3400);
WIRE 16 -1 (-4025 3225)(-3975 3225);
WIRE 16 -1 (-3975 3225)(-3975 3400);
WIRE 16 -1 (-3975 3225)(-3925 3225);
WIRE 16 -1 (-3925 3400)(-3925 3225);
WIRE 16 -1 (-3925 3225)(-3875 3225);
WIRE 16 -1 (-3875 3225)(-3825 3225);
WIRE 16 -1 (-3875 3225)(-3875 3400);
WIRE 16 -1 (-3825 3400)(-3825 3225);
WIRE 16 -1 (-3825 3225)(-3775 3225);
WIRE 16 -1 (-3775 3225)(-3775 3400);
WIRE 16 -1 (-3775 3225)(-3725 3225);
WIRE 16 -1 (-3725 3225)(-3725 3400);
WIRE 16 -1 (-3725 3225)(-3675 3225);
WIRE 16 -1 (-3675 3400)(-3675 3225);
WIRE 16 -1 (-3675 3225)(-3625 3225);
WIRE 16 -1 (-3625 3225)(-3575 3225);
WIRE 16 -1 (-3625 3225)(-3625 3400);
WIRE 16 -1 (-3575 3400)(-3575 3225);
WIRE 16 -1 (-3575 3225)(-3525 3225);
WIRE 16 -1 (-3525 3225)(-3525 3400);
WIRE 16 -1 (-3525 3225)(-3475 3225);
WIRE 16 -1 (-3475 3225)(-3475 3400);
WIRE 16 -1 (-3475 3225)(-3425 3225);
WIRE 16 -1 (-3425 3400)(-3425 3225);
WIRE 16 -1 (-3425 3225)(-3375 3225);
WIRE 16 -1 (-3375 3225)(-3325 3225);
WIRE 16 -1 (-3375 3225)(-3375 3400);
WIRE 16 -1 (-3325 3400)(-3325 3225);
WIRE 16 -1 (-3325 3225)(-3275 3225);
WIRE 16 -1 (-3275 3400)(-3275 3225);
WIRE 16 -1 (-3275 3225)(-3225 3225);
WIRE 16 -1 (-3225 3225)(-3225 3400);
WIRE 16 -1 (-3225 3225)(-3175 3225);
WIRE 16 -1 (-3175 3400)(-3175 3225);
WIRE 16 -1 (-3175 3225)(-3125 3225);
WIRE 16 -1 (-3125 3225)(-3125 3400);
WIRE 16 -1 (-3125 3225)(-3075 3225);
WIRE 16 -1 (-3075 3225)(-3025 3225);
WIRE 16 -1 (-3075 3225)(-3075 3400);
WIRE 16 -1 (-3025 3400)(-3025 3225);
WIRE 16 -1 (-3025 3225)(-2975 3225);
WIRE 16 -1 (-2975 3225)(-2975 3400);
WIRE 16 -1 (-2975 3225)(-2925 3225);
WIRE 16 -1 (-2925 3400)(-2925 3225);
WIRE 16 -1 (-2925 3225)(-2875 3225);
WIRE 16 -1 (-2875 3225)(-2875 3400);
WIRE 16 -1 (-2875 3225)(-2825 3225);
WIRE 16 -1 (-2825 3225)(-2775 3225);
WIRE 16 -1 (-2825 3225)(-2825 3400);
WIRE 16 -1 (-2775 3400)(-2775 3225);
WIRE 16 -1 (-2775 3225)(-2725 3225);
WIRE 16 -1 (-2725 3225)(-2725 3400);
WIRE 16 -1 (-2725 3225)(-2675 3225);
WIRE 16 -1 (-2675 3400)(-2675 3225);
WIRE 16 -1 (-2675 3225)(-2625 3225);
WIRE 16 -1 (-2625 3225)(-2625 3400);
WIRE 16 -1 (-2625 3225)(-2575 3225);
WIRE 16 -1 (-2575 3225)(-2525 3225);
WIRE 16 -1 (-2575 3225)(-2575 3400);
WIRE 16 -1 (-2525 3400)(-2525 3225);
WIRE 16 -1 (-2525 3225)(-2475 3225);
WIRE 16 -1 (-2475 3225)(-2475 3400);
WIRE 16 -1 (-2475 3225)(-2425 3225);
WIRE 16 -1 (-2425 3400)(-2425 3225);
WIRE 16 -1 (-2425 3225)(-2375 3225);
WIRE 16 -1 (-2375 3225)(-2375 3400);
WIRE 16 -1 (-2375 3225)(-2325 3225);
WIRE 16 -1 (-2325 3225)(-2275 3225);
WIRE 16 -1 (-2325 3225)(-2325 3400);
WIRE 16 -1 (-2275 3400)(-2275 3225);
WIRE 16 -1 (-2275 3225)(-2225 3225);
WIRE 16 -1 (-2225 3225)(-2225 3400);
WIRE 16 -1 (-2225 3225)(-2175 3225);
WIRE 16 -1 (-2175 3225)(-2175 3400);
WIRE 16 -1 (-2175 3225)(-2125 3225);
WIRE 16 -1 (-2125 3400)(-2125 3225);
WIRE 16 -1 (-2125 3225)(-2075 3225);
WIRE 16 -1 (-2075 3225)(-2025 3225);
WIRE 16 -1 (-2075 3400)(-2075 3225);
WIRE 16 -1 (-2025 3400)(-2025 3225);
WIRE 16 -1 (-2025 3225)(-1975 3225);
WIRE 16 -1 (-1975 3400)(-1975 3225);
WIRE 16 -1 (-1975 3225)(-1925 3225);
WIRE 16 -1 (-1925 3400)(-1925 3225);
WIRE 16 -1 (-1875 3225)(-1925 3225);
WIRE 16 -1 (-1700 3225)(-1875 3225);
WIRE 16 -1 (-1875 3400)(-1875 3225);
WIRE 16 -1 (-7775 4500)(-7775 4675);
WIRE 16 -1 (-7775 4675)(-7725 4675);
WIRE 16 -1 (-7725 4500)(-7725 4675);
WIRE 16 -1 (-7725 4675)(-7675 4675);
WIRE 16 -1 (-7675 4675)(-7625 4675);
WIRE 16 -1 (-7675 4500)(-7675 4675);
WIRE 16 -1 (-7625 4500)(-7625 4675);
WIRE 16 -1 (-7625 4675)(-7575 4675);
WIRE 16 -1 (-7575 4500)(-7575 4675);
WIRE 16 -1 (-7575 4675)(-7525 4675);
WIRE 16 -1 (-7525 4500)(-7525 4675);
WIRE 16 -1 (-7525 4675)(-7475 4675);
WIRE 16 -1 (-7475 4500)(-7475 4675);
WIRE 16 -1 (-7475 4675)(-7425 4675);
WIRE 16 -1 (-7425 4500)(-7425 4675);
WIRE 16 -1 (-7425 4675)(-7375 4675);
WIRE 16 -1 (-7375 4500)(-7375 4675);
WIRE 16 -1 (-7375 4675)(-7325 4675);
WIRE 16 -1 (-7325 4500)(-7325 4675);
WIRE 16 -1 (-7325 4675)(-7275 4675);
WIRE 16 -1 (-7275 4500)(-7275 4675);
WIRE 16 -1 (-7275 4675)(-7225 4675);
WIRE 16 -1 (-7225 4500)(-7225 4675);
WIRE 16 -1 (-7225 4675)(-7175 4675);
WIRE 16 -1 (-7175 4500)(-7175 4675);
WIRE 16 -1 (-7175 4675)(-7125 4675);
WIRE 16 -1 (-7125 4675)(-7075 4675);
WIRE 16 -1 (-7125 4500)(-7125 4675);
WIRE 16 -1 (-7075 4500)(-7075 4675);
WIRE 16 -1 (-7075 4675)(-7025 4675);
WIRE 16 -1 (-7025 4500)(-7025 4675);
WIRE 16 -1 (-7025 4675)(-6975 4675);
WIRE 16 -1 (-6975 4500)(-6975 4675);
WIRE 16 -1 (-6975 4675)(-6925 4675);
WIRE 16 -1 (-6925 4500)(-6925 4675);
WIRE 16 -1 (-6925 4675)(-6875 4675);
WIRE 16 -1 (-6875 4500)(-6875 4675);
WIRE 16 -1 (-6875 4675)(-6825 4675);
WIRE 16 -1 (-6825 4500)(-6825 4675);
WIRE 16 -1 (-6825 4675)(-6775 4675);
WIRE 16 -1 (-6775 4500)(-6775 4675);
WIRE 16 -1 (-6775 4675)(-6725 4675);
WIRE 16 -1 (-6725 4500)(-6725 4675);
WIRE 16 -1 (-6725 4675)(-6675 4675);
WIRE 16 -1 (-6675 4500)(-6675 4675);
WIRE 16 -1 (-6675 4675)(-6625 4675);
WIRE 16 -1 (-6625 4675)(-6575 4675);
WIRE 16 -1 (-6625 4500)(-6625 4675);
WIRE 16 -1 (-6575 4500)(-6575 4675);
WIRE 16 -1 (-6575 4675)(-6525 4675);
WIRE 16 -1 (-6525 4500)(-6525 4675);
WIRE 16 -1 (-6525 4675)(-6475 4675);
WIRE 16 -1 (-6475 4500)(-6475 4675);
WIRE 16 -1 (-6475 4675)(-6425 4675);
WIRE 16 -1 (-6425 4500)(-6425 4675);
WIRE 16 -1 (-6425 4675)(-6375 4675);
WIRE 16 -1 (-6375 4500)(-6375 4675);
WIRE 16 -1 (-6375 4675)(-6325 4675);
WIRE 16 -1 (-6325 4500)(-6325 4675);
WIRE 16 -1 (-6325 4675)(-6275 4675);
WIRE 16 -1 (-6275 4500)(-6275 4675);
WIRE 16 -1 (-6275 4675)(-6225 4675);
WIRE 16 -1 (-6225 4500)(-6225 4675);
WIRE 16 -1 (-6225 4675)(-6175 4675);
WIRE 16 -1 (-6175 4500)(-6175 4675);
WIRE 16 -1 (-6175 4675)(-6125 4675);
WIRE 16 -1 (-6125 4675)(-6075 4675);
WIRE 16 -1 (-6125 4500)(-6125 4675);
WIRE 16 -1 (-6075 4500)(-6075 4675);
WIRE 16 -1 (-6075 4675)(-6025 4675);
WIRE 16 -1 (-6025 4500)(-6025 4675);
WIRE 16 -1 (-6025 4675)(-5975 4675);
WIRE 16 -1 (-5975 4500)(-5975 4675);
WIRE 16 -1 (-5975 4675)(-5925 4675);
WIRE 16 -1 (-5925 4500)(-5925 4675);
WIRE 16 -1 (-5925 4675)(-5875 4675);
WIRE 16 -1 (-5875 4500)(-5875 4675);
WIRE 16 -1 (-5875 4675)(-5825 4675);
WIRE 16 -1 (-5825 4500)(-5825 4675);
WIRE 16 -1 (-5825 4675)(-5775 4675);
WIRE 16 -1 (-5775 4500)(-5775 4675);
WIRE 16 -1 (-5775 4675)(-5725 4675);
WIRE 16 -1 (-5725 4500)(-5725 4675);
WIRE 16 -1 (-5725 4675)(-5675 4675);
WIRE 16 -1 (-5675 4500)(-5675 4675);
WIRE 16 -1 (-5675 4675)(-5625 4675);
WIRE 16 -1 (-5625 4675)(-5575 4675);
WIRE 16 -1 (-5625 4500)(-5625 4675);
WIRE 16 -1 (-5575 4500)(-5575 4675);
WIRE 16 -1 (-5575 4675)(-5525 4675);
WIRE 16 -1 (-5525 4500)(-5525 4675);
WIRE 16 -1 (-5525 4675)(-5475 4675);
WIRE 16 -1 (-5475 4500)(-5475 4675);
WIRE 16 -1 (-5475 4675)(-5425 4675);
WIRE 16 -1 (-5425 4500)(-5425 4675);
WIRE 16 -1 (-5425 4675)(-5375 4675);
WIRE 16 -1 (-5375 4500)(-5375 4675);
WIRE 16 -1 (-5375 4675)(-5325 4675);
WIRE 16 -1 (-5325 4500)(-5325 4675);
WIRE 16 -1 (-5325 4675)(-5275 4675);
WIRE 16 -1 (-5275 4500)(-5275 4675);
WIRE 16 -1 (-5275 4675)(-5225 4675);
WIRE 16 -1 (-5225 4500)(-5225 4675);
WIRE 16 -1 (-5225 4675)(-5175 4675);
WIRE 16 -1 (-5175 4500)(-5175 4675);
WIRE 16 -1 (-5175 4675)(-5125 4675);
WIRE 16 -1 (-5125 4500)(-5125 4675);
WIRE 16 -1 (-5125 4675)(-5075 4675);
WIRE 16 -1 (-5075 4675)(-5025 4675);
WIRE 16 -1 (-5075 4500)(-5075 4675);
WIRE 16 -1 (-5025 4500)(-5025 4675);
WIRE 16 -1 (-5025 4675)(-4975 4675);
WIRE 16 -1 (-4975 4500)(-4975 4675);
WIRE 16 -1 (-4975 4675)(-4925 4675);
WIRE 16 -1 (-4925 4500)(-4925 4675);
WIRE 16 -1 (-4925 4675)(-4875 4675);
WIRE 16 -1 (-4875 4500)(-4875 4675);
WIRE 16 -1 (-4875 4675)(-4825 4675);
WIRE 16 -1 (-4825 4500)(-4825 4675);
WIRE 16 -1 (-4825 4675)(-4775 4675);
WIRE 16 -1 (-4775 4500)(-4775 4675);
WIRE 16 -1 (-4775 4675)(-4725 4675);
WIRE 16 -1 (-4725 4500)(-4725 4675);
WIRE 16 -1 (-4725 4675)(-4675 4675);
WIRE 16 -1 (-4675 4500)(-4675 4675);
WIRE 16 -1 (-4675 4675)(-4625 4675);
WIRE 16 -1 (-4625 4500)(-4625 4675);
WIRE 16 -1 (-4625 4675)(-4575 4675);
WIRE 16 -1 (-4575 4675)(-4525 4675);
WIRE 16 -1 (-4575 4500)(-4575 4675);
WIRE 16 -1 (-4525 4500)(-4525 4675);
WIRE 16 -1 (-4525 4675)(-4475 4675);
WIRE 16 -1 (-4475 4500)(-4475 4675);
WIRE 16 -1 (-4475 4675)(-4425 4675);
WIRE 16 -1 (-4425 4500)(-4425 4675);
WIRE 16 -1 (-4425 4675)(-4375 4675);
WIRE 16 -1 (-4375 4500)(-4375 4675);
WIRE 16 -1 (-4375 4675)(-4325 4675);
WIRE 16 -1 (-4325 4500)(-4325 4675);
WIRE 16 -1 (-4325 4675)(-4275 4675);
WIRE 16 -1 (-4275 4500)(-4275 4675);
WIRE 16 -1 (-4275 4675)(-4225 4675);
WIRE 16 -1 (-4225 4500)(-4225 4675);
WIRE 16 -1 (-4225 4675)(-4175 4675);
WIRE 16 -1 (-4175 4500)(-4175 4675);
WIRE 16 -1 (-4175 4675)(-4125 4675);
WIRE 16 -1 (-4125 4500)(-4125 4675);
WIRE 16 -1 (-4125 4675)(-4075 4675);
WIRE 16 -1 (-4075 4675)(-4025 4675);
WIRE 16 -1 (-4075 4500)(-4075 4675);
WIRE 16 -1 (-4025 4500)(-4025 4675);
WIRE 16 -1 (-4025 4675)(-3975 4675);
WIRE 16 -1 (-3975 4500)(-3975 4675);
WIRE 16 -1 (-3975 4675)(-3925 4675);
WIRE 16 -1 (-3925 4500)(-3925 4675);
WIRE 16 -1 (-3925 4675)(-3875 4675);
WIRE 16 -1 (-3875 4500)(-3875 4675);
WIRE 16 -1 (-3875 4675)(-3825 4675);
WIRE 16 -1 (-3825 4500)(-3825 4675);
WIRE 16 -1 (-3825 4675)(-3775 4675);
WIRE 16 -1 (-3775 4500)(-3775 4675);
WIRE 16 -1 (-3775 4675)(-3725 4675);
WIRE 16 -1 (-3725 4500)(-3725 4675);
WIRE 16 -1 (-3725 4675)(-3675 4675);
WIRE 16 -1 (-3675 4500)(-3675 4675);
WIRE 16 -1 (-3675 4675)(-3625 4675);
WIRE 16 -1 (-3625 4500)(-3625 4675);
WIRE 16 -1 (-3625 4675)(-3575 4675);
WIRE 16 -1 (-3575 4675)(-3525 4675);
WIRE 16 -1 (-3575 4500)(-3575 4675);
WIRE 16 -1 (-3525 4500)(-3525 4675);
WIRE 16 -1 (-3525 4675)(-3475 4675);
WIRE 16 -1 (-3475 4500)(-3475 4675);
WIRE 16 -1 (-3475 4675)(-3425 4675);
WIRE 16 -1 (-3425 4500)(-3425 4675);
WIRE 16 -1 (-3425 4675)(-3375 4675);
WIRE 16 -1 (-3375 4500)(-3375 4675);
WIRE 16 -1 (-3375 4675)(-3325 4675);
WIRE 16 -1 (-3325 4500)(-3325 4675);
WIRE 16 -1 (-3325 4675)(-3275 4675);
WIRE 16 -1 (-3275 4500)(-3275 4675);
WIRE 16 -1 (-3275 4675)(-3225 4675);
WIRE 16 -1 (-3225 4500)(-3225 4675);
WIRE 16 -1 (-3225 4675)(-3175 4675);
WIRE 16 -1 (-3175 4500)(-3175 4675);
WIRE 16 -1 (-3175 4675)(-3125 4675);
WIRE 16 -1 (-3125 4500)(-3125 4675);
WIRE 16 -1 (-3125 4675)(-3075 4675);
WIRE 16 -1 (-3075 4500)(-3075 4675);
WIRE 16 -1 (-3075 4675)(-3025 4675);
WIRE 16 -1 (-3025 4675)(-2975 4675);
WIRE 16 -1 (-3025 4500)(-3025 4675);
WIRE 16 -1 (-2975 4500)(-2975 4675);
WIRE 16 -1 (-2975 4675)(-2925 4675);
WIRE 16 -1 (-2925 4500)(-2925 4675);
WIRE 16 -1 (-2925 4675)(-2875 4675);
WIRE 16 -1 (-2875 4500)(-2875 4675);
WIRE 16 -1 (-2875 4675)(-2825 4675);
WIRE 16 -1 (-2825 4500)(-2825 4675);
WIRE 16 -1 (-2825 4675)(-2775 4675);
WIRE 16 -1 (-2775 4500)(-2775 4675);
WIRE 16 -1 (-2775 4675)(-2725 4675);
WIRE 16 -1 (-2725 4500)(-2725 4675);
WIRE 16 -1 (-2725 4675)(-2675 4675);
WIRE 16 -1 (-2675 4500)(-2675 4675);
WIRE 16 -1 (-2675 4675)(-2625 4675);
WIRE 16 -1 (-2625 4500)(-2625 4675);
WIRE 16 -1 (-2625 4675)(-2575 4675);
WIRE 16 -1 (-2575 4500)(-2575 4675);
WIRE 16 -1 (-2575 4675)(-2525 4675);
WIRE 16 -1 (-2525 4675)(-2475 4675);
WIRE 16 -1 (-2525 4500)(-2525 4675);
WIRE 16 -1 (-2475 4500)(-2475 4675);
WIRE 16 -1 (-2475 4675)(-2425 4675);
WIRE 16 -1 (-2425 4500)(-2425 4675);
WIRE 16 -1 (-2425 4675)(-2375 4675);
WIRE 16 -1 (-2375 4500)(-2375 4675);
WIRE 16 -1 (-2375 4675)(-2325 4675);
WIRE 16 -1 (-2325 4500)(-2325 4675);
WIRE 16 -1 (-2325 4675)(-2275 4675);
WIRE 16 -1 (-2275 4500)(-2275 4675);
WIRE 16 -1 (-2275 4675)(-2225 4675);
WIRE 16 -1 (-2225 4500)(-2225 4675);
WIRE 16 -1 (-2225 4675)(-2175 4675);
WIRE 16 -1 (-2175 4500)(-2175 4675);
WIRE 16 -1 (-2175 4675)(-2125 4675);
WIRE 16 -1 (-2125 4500)(-2125 4675);
WIRE 16 -1 (-2125 4675)(-2075 4675);
WIRE 16 -1 (-2075 4500)(-2075 4675);
WIRE 16 -1 (-2075 4675)(-2025 4675);
WIRE 16 -1 (-2025 4675)(-1975 4675);
WIRE 16 -1 (-2025 4500)(-2025 4675);
WIRE 16 -1 (-1975 4500)(-1975 4675);
WIRE 16 -1 (-1975 4675)(-1925 4675);
WIRE 16 -1 (-1925 4500)(-1925 4675);
WIRE 16 -1 (-1875 4675)(-1925 4675);
WIRE 16 -1 (-1875 4500)(-1875 4675);
WIRE 16 -1 (-1825 4675)(-1875 4675);
WIRE 16 -1 (-1825 4500)(-1825 4675);
WIRE 16 -1 (-1775 4675)(-1825 4675);
WIRE 16 -1 (-1775 4500)(-1775 4675);
WIRE 16 -1 (-1725 4675)(-1775 4675);
WIRE 16 -1 (-1725 4500)(-1725 4675);
WIRE 16 -1 (-1675 4675)(-1725 4675);
WIRE 16 -1 (-1675 4500)(-1675 4675);
WIRE 16 -1 (-1625 4675)(-1675 4675);
WIRE 16 -1 (-1625 4500)(-1625 4675);
WIRE 16 -1 (-1575 4675)(-1625 4675);
WIRE 16 -1 (-1575 4500)(-1575 4675);
WIRE 16 -1 (-1525 4675)(-1575 4675);
WIRE 16 -1 (-1475 4675)(-1525 4675);
WIRE 16 -1 (-1525 4675)(-1525 4500);
WIRE 16 -1 (-1425 4675)(-1475 4675);
WIRE 16 -1 (-1475 4675)(-1475 4500);
WIRE 16 -1 (-1375 4675)(-1425 4675);
WIRE 16 -1 (-1425 4675)(-1425 4500);
WIRE 16 -1 (-1125 4675)(-1375 4675);
WIRE 16 -1 (-1375 4675)(-1375 4500);
DOT 1 (-4525 4675);
DOT 1 (-7725 3225);
DOT 1 (-7675 3225);
DOT 1 (-7625 3225);
DOT 1 (-7525 3225);
DOT 1 (-7475 3225);
DOT 1 (-7425 3225);
DOT 1 (-7375 3225);
DOT 1 (-7325 3225);
DOT 1 (-7275 3225);
DOT 1 (-7225 3225);
DOT 1 (-7175 3225);
DOT 1 (-7125 3225);
DOT 1 (-7075 3225);
DOT 1 (-7025 3225);
DOT 1 (-6975 3225);
DOT 1 (-6925 3225);
DOT 1 (-6875 3225);
DOT 1 (-6825 3225);
DOT 1 (-6775 3225);
DOT 1 (-6725 3225);
DOT 1 (-6675 3225);
DOT 1 (-6625 3225);
DOT 1 (-6575 3225);
DOT 1 (-6525 3225);
DOT 1 (-6475 3225);
DOT 1 (-6425 3225);
DOT 1 (-6375 3225);
DOT 1 (-6325 3225);
DOT 1 (-6275 3225);
DOT 1 (-6225 3225);
DOT 1 (-6175 3225);
DOT 1 (-6125 3225);
DOT 1 (-6075 3225);
DOT 1 (-6025 3225);
DOT 1 (-5975 3225);
DOT 1 (-5925 3225);
DOT 1 (-5875 3225);
DOT 1 (-5825 3225);
DOT 1 (-5775 3225);
DOT 1 (-5725 3225);
DOT 1 (-5675 3225);
DOT 1 (-5625 3225);
DOT 1 (-5575 3225);
DOT 1 (-5525 3225);
DOT 1 (-5475 3225);
DOT 1 (-5425 3225);
DOT 1 (-5375 3225);
DOT 1 (-5325 3225);
DOT 1 (-5275 3225);
DOT 1 (-5225 3225);
DOT 1 (-5175 3225);
DOT 1 (-5125 3225);
DOT 1 (-5075 3225);
DOT 1 (-5025 3225);
DOT 1 (-4975 3225);
DOT 1 (-4925 3225);
DOT 1 (-4875 3225);
DOT 1 (-4825 3225);
DOT 1 (-4775 3225);
DOT 1 (-4725 3225);
DOT 1 (-4675 3225);
DOT 1 (-4625 3225);
DOT 1 (-4575 3225);
DOT 1 (-4525 3225);
DOT 1 (-4475 3225);
DOT 1 (-4425 3225);
DOT 1 (-4375 3225);
DOT 1 (-4325 3225);
DOT 1 (-4275 3225);
DOT 1 (-4225 3225);
DOT 1 (-4175 3225);
DOT 1 (-4125 3225);
DOT 1 (-4075 3225);
DOT 1 (-4025 3225);
DOT 1 (-3975 3225);
DOT 1 (-3925 3225);
DOT 1 (-3875 3225);
DOT 1 (-7725 4675);
DOT 1 (-7675 4675);
DOT 1 (-7625 4675);
DOT 1 (-7575 4675);
DOT 1 (-7475 4675);
DOT 1 (-7525 4675);
DOT 1 (-7425 4675);
DOT 1 (-7375 4675);
DOT 1 (-7325 4675);
DOT 1 (-7225 4675);
DOT 1 (-7275 4675);
DOT 1 (-7075 4675);
DOT 1 (-7125 4675);
DOT 1 (-7175 4675);
DOT 1 (-7025 4675);
DOT 1 (-6975 4675);
DOT 1 (-6825 4675);
DOT 1 (-6875 4675);
DOT 1 (-6925 4675);
DOT 1 (-6775 4675);
DOT 1 (-6725 4675);
DOT 1 (-6675 4675);
DOT 1 (-6575 4675);
DOT 1 (-6625 4675);
DOT 1 (-6525 4675);
DOT 1 (-6475 4675);
DOT 1 (-6425 4675);
DOT 1 (-6325 4675);
DOT 1 (-6375 4675);
DOT 1 (-6275 4675);
DOT 1 (-6225 4675);
DOT 1 (-6175 4675);
DOT 1 (-6125 4675);
DOT 1 (-6075 4675);
DOT 1 (-5975 4675);
DOT 1 (-5925 4675);
DOT 1 (-6025 4675);
DOT 1 (-5875 4675);
DOT 1 (-5825 4675);
DOT 1 (-5725 4675);
DOT 1 (-5675 4675);
DOT 1 (-5775 4675);
DOT 1 (-5625 4675);
DOT 1 (-5575 4675);
DOT 1 (-5525 4675);
DOT 1 (-5425 4675);
DOT 1 (-5475 4675);
DOT 1 (-5375 4675);
DOT 1 (-5325 4675);
DOT 1 (-5275 4675);
DOT 1 (-5175 4675);
DOT 1 (-5225 4675);
DOT 1 (-5025 4675);
DOT 1 (-5075 4675);
DOT 1 (-5125 4675);
DOT 1 (-4975 4675);
DOT 1 (-4925 4675);
DOT 1 (-4775 4675);
DOT 1 (-4825 4675);
DOT 1 (-4875 4675);
DOT 1 (-4725 4675);
DOT 1 (-4675 4675);
DOT 1 (-4625 4675);
DOT 1 (-4575 4675);
DOT 1 (-4475 4675);
DOT 1 (-4425 4675);
DOT 1 (-4375 4675);
DOT 1 (-4275 4675);
DOT 1 (-4325 4675);
DOT 1 (-4225 4675);
DOT 1 (-4175 4675);
DOT 1 (-4125 4675);
DOT 1 (-4025 4675);
DOT 1 (-4075 4675);
DOT 1 (-3875 4675);
DOT 1 (-3925 4675);
DOT 1 (-3975 4675);
DOT 1 (-3825 3225);
DOT 1 (-3775 3225);
DOT 1 (-3725 3225);
DOT 1 (-3675 3225);
DOT 1 (-3625 3225);
DOT 1 (-3575 3225);
DOT 1 (-3525 3225);
DOT 1 (-3475 3225);
DOT 1 (-3425 3225);
DOT 1 (-3375 3225);
DOT 1 (-3275 3225);
DOT 1 (-3325 3225);
DOT 1 (-3225 3225);
DOT 1 (-3175 3225);
DOT 1 (-3125 3225);
DOT 1 (-3075 3225);
DOT 1 (-3025 3225);
DOT 1 (-2975 3225);
DOT 1 (-2925 3225);
DOT 1 (-2875 3225);
DOT 1 (-2825 3225);
DOT 1 (-2775 3225);
DOT 1 (-2725 3225);
DOT 1 (-2675 3225);
DOT 1 (-2625 3225);
DOT 1 (-2575 3225);
DOT 1 (-2525 3225);
DOT 1 (-2475 3225);
DOT 1 (-2425 3225);
DOT 1 (-2375 3225);
DOT 1 (-2325 3225);
DOT 1 (-2275 3225);
DOT 1 (-2225 3225);
DOT 1 (-2175 3225);
DOT 1 (-2125 3225);
DOT 1 (-2075 3225);
DOT 1 (-2025 3225);
DOT 1 (-1975 3225);
DOT 1 (-1925 3225);
DOT 1 (-1875 3225);
DOT 1 (-3825 4675);
DOT 1 (-3775 4675);
DOT 1 (-3675 4675);
DOT 1 (-3625 4675);
DOT 1 (-3725 4675);
DOT 1 (-3575 4675);
DOT 1 (-3525 4675);
DOT 1 (-3475 4675);
DOT 1 (-3375 4675);
DOT 1 (-3425 4675);
DOT 1 (-3275 4675);
DOT 1 (-3325 4675);
DOT 1 (-3225 4675);
DOT 1 (-3125 4675);
DOT 1 (-3175 4675);
DOT 1 (-3075 4675);
DOT 1 (-3025 4675);
DOT 1 (-2975 4675);
DOT 1 (-2925 4675);
DOT 1 (-2875 4675);
DOT 1 (-2725 4675);
DOT 1 (-2775 4675);
DOT 1 (-2825 4675);
DOT 1 (-2675 4675);
DOT 1 (-2625 4675);
DOT 1 (-2475 4675);
DOT 1 (-2525 4675);
DOT 1 (-2575 4675);
DOT 1 (-2425 4675);
DOT 1 (-2375 4675);
DOT 1 (-2325 4675);
DOT 1 (-2225 4675);
DOT 1 (-2275 4675);
DOT 1 (-2175 4675);
DOT 1 (-2125 4675);
DOT 1 (-2075 4675);
DOT 1 (-1975 4675);
DOT 1 (-2025 4675);
DOT 1 (-1825 4675);
DOT 1 (-1875 4675);
DOT 1 (-1925 4675);
DOT 1 (-1775 4675);
DOT 1 (-1725 4675);
DOT 1 (-1625 4675);
DOT 1 (-1575 4675);
DOT 1 (-1675 4675);
DOT 1 (-1525 4675);
DOT 1 (-1475 4675);
DOT 1 (-1425 4675);
DOT 1 (-1375 4675);
DOT 1 (-7575 3225);
QUIT
